(kicad_pcb
	(version 20260206)
	(generator "pcbnew")
	(generator_version "10.0")
	(general
		(thickness 1.6)
		(legacy_teardrops no)
	)
	(paper "A4")
	(title_block
		(title "12092022_DA0F0TYB4D0_F0T_Panel_BD_Front_D_brd_v02_OCP.brd")
		(comment 1 "Grand Teton / footprints 10-15 of 128")
	)
	(layers
		(0 "F.Cu" signal "TOP")
		(4 "In1.Cu" signal "GND")
		(6 "In2.Cu" signal "GND1")
		(2 "B.Cu" signal "BOTTOM")
		(9 "F.Adhes" user "F.Adhesive")
		(11 "B.Adhes" user "B.Adhesive")
		(13 "F.Paste" user "Package Geometry/Pastemask Top")
		(15 "B.Paste" user "Package Geometry/Pastemask Bottom")
		(5 "F.SilkS" user "Ref Des/Silkscreen Top")
		(7 "B.SilkS" user "Ref Des/Silkscreen Bottom")
		(1 "F.Mask" user "Board Geometry/Soldermask Top")
		(3 "B.Mask" user "Board Geometry/Soldermask Bottom")
		(17 "Dwgs.User" user "User.Drawings")
		(19 "Cmts.User" user "User.Comments")
		(21 "Eco1.User" user "User.Eco1")
		(23 "Eco2.User" user "User.Eco2")
		(25 "Edge.Cuts" user "Board Geometry/Outline")
		(27 "Margin" user)
		(31 "F.CrtYd" user "Package Geometry/Place Bound Top")
		(29 "B.CrtYd" user "Package Geometry/Place Bound Bottom")
		(35 "F.Fab" user "Ref Des/Assembly Top")
		(33 "B.Fab" user "Ref Des/Assembly Bottom")
	)
	(footprint ""
		(layer "F.Cu")
		(at 36.703 -24.384)
		(property "Reference" "R39"
			(at -2.032 0.02667 0)
			(unlocked yes)
			(layer "F.SilkS")
			(effects
				(font
					(size 0.7874 0.5842)
					(thickness 0.1524)
				)
			)
		)
		(property "Value" ""
			(at 0 0 0)
			(layer "F.Fab")
			(effects
				(font
					(size 1.27 1.27)
				)
			)
		)
		(duplicate_pad_numbers_are_jumpers no)
		(fp_line
			(start -0.7874 -0.4064)
			(end 0.7874 -0.4064)
			(stroke
				(width 0.1524)
				(type default)
			)
			(layer "F.SilkS")
		)
		(fp_line
			(start -0.7874 0.4064)
			(end -0.7874 -0.4064)
			(stroke
				(width 0.1524)
				(type default)
			)
			(layer "F.SilkS")
		)
		(fp_line
			(start 0.7874 -0.4064)
			(end 0.7874 0.4064)
			(stroke
				(width 0.1524)
				(type default)
			)
			(layer "F.SilkS")
		)
		(fp_line
			(start 0.7874 0.4064)
			(end -0.7874 0.4064)
			(stroke
				(width 0.1524)
				(type default)
			)
			(layer "F.SilkS")
		)
		(fp_line
			(start -0.67945 -0.305054)
			(end -0.12065 -0.305054)
			(stroke
				(width 0.1)
				(type default)
			)
			(layer "F.Fab")
		)
		(fp_line
			(start -0.67945 0.3048)
			(end -0.67945 -0.305054)
			(stroke
				(width 0.1)
				(type default)
			)
			(layer "F.Fab")
		)
		(fp_line
			(start -0.12065 -0.305054)
			(end -0.12065 -0.2794)
			(stroke
				(width 0.1)
				(type default)
			)
			(layer "F.Fab")
		)
		(fp_line
			(start -0.12065 -0.2794)
			(end 0.12065 -0.2794)
			(stroke
				(width 0.1)
				(type default)
			)
			(layer "F.Fab")
		)
		(fp_line
			(start -0.12065 0.2794)
			(end -0.12065 0.3048)
			(stroke
				(width 0.1)
				(type default)
			)
			(layer "F.Fab")
		)
		(fp_line
			(start -0.12065 0.3048)
			(end -0.67945 0.3048)
			(stroke
				(width 0.1)
				(type default)
			)
			(layer "F.Fab")
		)
		(fp_line
			(start 0.120396 0.2794)
			(end -0.12065 0.2794)
			(stroke
				(width 0.1)
				(type default)
			)
			(layer "F.Fab")
		)
		(fp_line
			(start 0.120396 0.3048)
			(end 0.120396 0.2794)
			(stroke
				(width 0.1)
				(type default)
			)
			(layer "F.Fab")
		)
		(fp_line
			(start 0.12065 -0.3048)
			(end 0.67945 -0.3048)
			(stroke
				(width 0.1)
				(type default)
			)
			(layer "F.Fab")
		)
		(fp_line
			(start 0.12065 -0.2794)
			(end 0.12065 -0.3048)
			(stroke
				(width 0.1)
				(type default)
			)
			(layer "F.Fab")
		)
		(fp_line
			(start 0.67945 -0.3048)
			(end 0.67945 0.3048)
			(stroke
				(width 0.1)
				(type default)
			)
			(layer "F.Fab")
		)
		(fp_line
			(start 0.67945 0.3048)
			(end 0.120396 0.3048)
			(stroke
				(width 0.1)
				(type default)
			)
			(layer "F.Fab")
		)
		(pad "1" smd circle
			(at -0.40005 0)
			(size 0 0)
			(layers "F.Cu" "F.Mask" "F.Paste")
			(net "THERMAL_ADDR_A2")
		)
		(pad "2" smd circle
			(at 0.40005 0)
			(size 0 0)
			(layers "F.Cu" "F.Mask" "F.Paste")
			(net "GND")
		)
	)
	(footprint ""
		(layer "F.Cu")
		(at 13.462 -27.94 180)
		(property "Reference" "R44"
			(at -0.127 0.98933 0)
			(unlocked yes)
			(layer "F.SilkS")
			(effects
				(font
					(size 0.7874 0.5842)
					(thickness 0.1524)
				)
			)
		)
		(property "Value" ""
			(at 0 0 180)
			(layer "F.Fab")
			(effects
				(font
					(size 1.27 1.27)
				)
			)
		)
		(duplicate_pad_numbers_are_jumpers no)
		(fp_line
			(start 0.7874 0.4064)
			(end -0.7874 0.4064)
			(stroke
				(width 0.1524)
				(type default)
			)
			(layer "F.SilkS")
		)
		(fp_line
			(start 0.7874 -0.4064)
			(end 0.7874 0.4064)
			(stroke
				(width 0.1524)
				(type default)
			)
			(layer "F.SilkS")
		)
		(fp_line
			(start -0.7874 0.4064)
			(end -0.7874 -0.4064)
			(stroke
				(width 0.1524)
				(type default)
			)
			(layer "F.SilkS")
		)
		(fp_line
			(start -0.7874 -0.4064)
			(end 0.7874 -0.4064)
			(stroke
				(width 0.1524)
				(type default)
			)
			(layer "F.SilkS")
		)
		(fp_line
			(start 0.67945 0.3048)
			(end 0.120396 0.3048)
			(stroke
				(width 0.1)
				(type default)
			)
			(layer "F.Fab")
		)
		(fp_line
			(start 0.67945 -0.3048)
			(end 0.67945 0.3048)
			(stroke
				(width 0.1)
				(type default)
			)
			(layer "F.Fab")
		)
		(fp_line
			(start 0.12065 -0.2794)
			(end 0.12065 -0.3048)
			(stroke
				(width 0.1)
				(type default)
			)
			(layer "F.Fab")
		)
		(fp_line
			(start 0.12065 -0.3048)
			(end 0.67945 -0.3048)
			(stroke
				(width 0.1)
				(type default)
			)
			(layer "F.Fab")
		)
		(fp_line
			(start 0.120396 0.3048)
			(end 0.120396 0.2794)
			(stroke
				(width 0.1)
				(type default)
			)
			(layer "F.Fab")
		)
		(fp_line
			(start 0.120396 0.2794)
			(end -0.12065 0.2794)
			(stroke
				(width 0.1)
				(type default)
			)
			(layer "F.Fab")
		)
		(fp_line
			(start -0.12065 0.3048)
			(end -0.67945 0.3048)
			(stroke
				(width 0.1)
				(type default)
			)
			(layer "F.Fab")
		)
		(fp_line
			(start -0.12065 0.2794)
			(end -0.12065 0.3048)
			(stroke
				(width 0.1)
				(type default)
			)
			(layer "F.Fab")
		)
		(fp_line
			(start -0.12065 -0.2794)
			(end 0.12065 -0.2794)
			(stroke
				(width 0.1)
				(type default)
			)
			(layer "F.Fab")
		)
		(fp_line
			(start -0.12065 -0.305054)
			(end -0.12065 -0.2794)
			(stroke
				(width 0.1)
				(type default)
			)
			(layer "F.Fab")
		)
		(fp_line
			(start -0.67945 0.3048)
			(end -0.67945 -0.305054)
			(stroke
				(width 0.1)
				(type default)
			)
			(layer "F.Fab")
		)
		(fp_line
			(start -0.67945 -0.305054)
			(end -0.12065 -0.305054)
			(stroke
				(width 0.1)
				(type default)
			)
			(layer "F.Fab")
		)
		(pad "1" smd circle
			(at -0.40005 0 180)
			(size 0 0)
			(layers "F.Cu" "F.Mask" "F.Paste")
			(net "P3V3_STBY")
		)
		(pad "2" smd circle
			(at 0.40005 0 180)
			(size 0 0)
			(layers "F.Cu" "F.Mask" "F.Paste")
			(net "PRSNT_DBV2_USB_N")
		)
	)
	(footprint ""
		(layer "F.Cu")
		(at 29.591 -33.02)
		(property "Reference" "C13"
			(at -2.032 0.02667 0)
			(unlocked yes)
			(layer "F.SilkS")
			(effects
				(font
					(size 0.7874 0.5842)
					(thickness 0.1524)
				)
			)
		)
		(property "Value" ""
			(at 0 0 0)
			(layer "F.Fab")
			(effects
				(font
					(size 1.27 1.27)
				)
			)
		)
		(duplicate_pad_numbers_are_jumpers no)
		(fp_line
			(start -0.7874 -0.4064)
			(end 0.7874 -0.4064)
			(stroke
				(width 0.1524)
				(type default)
			)
			(layer "F.SilkS")
		)
		(fp_line
			(start -0.7874 0.4064)
			(end -0.7874 -0.4064)
			(stroke
				(width 0.1524)
				(type default)
			)
			(layer "F.SilkS")
		)
		(fp_line
			(start 0.7874 -0.4064)
			(end 0.7874 0.4064)
			(stroke
				(width 0.1524)
				(type default)
			)
			(layer "F.SilkS")
		)
		(fp_line
			(start 0.7874 0.4064)
			(end -0.7874 0.4064)
			(stroke
				(width 0.1524)
				(type default)
			)
			(layer "F.SilkS")
		)
		(fp_line
			(start -0.67945 -0.305054)
			(end -0.12065 -0.305054)
			(stroke
				(width 0.1)
				(type default)
			)
			(layer "F.Fab")
		)
		(fp_line
			(start -0.67945 0.3048)
			(end -0.67945 -0.305054)
			(stroke
				(width 0.1)
				(type default)
			)
			(layer "F.Fab")
		)
		(fp_line
			(start -0.12065 -0.305054)
			(end -0.12065 -0.2794)
			(stroke
				(width 0.1)
				(type default)
			)
			(layer "F.Fab")
		)
		(fp_line
			(start -0.12065 -0.2794)
			(end 0.12065 -0.2794)
			(stroke
				(width 0.1)
				(type default)
			)
			(layer "F.Fab")
		)
		(fp_line
			(start -0.12065 0.2794)
			(end -0.12065 0.3048)
			(stroke
				(width 0.1)
				(type default)
			)
			(layer "F.Fab")
		)
		(fp_line
			(start -0.12065 0.3048)
			(end -0.67945 0.3048)
			(stroke
				(width 0.1)
				(type default)
			)
			(layer "F.Fab")
		)
		(fp_line
			(start 0.120396 0.2794)
			(end -0.12065 0.2794)
			(stroke
				(width 0.1)
				(type default)
			)
			(layer "F.Fab")
		)
		(fp_line
			(start 0.120396 0.3048)
			(end 0.120396 0.2794)
			(stroke
				(width 0.1)
				(type default)
			)
			(layer "F.Fab")
		)
		(fp_line
			(start 0.12065 -0.3048)
			(end 0.67945 -0.3048)
			(stroke
				(width 0.1)
				(type default)
			)
			(layer "F.Fab")
		)
		(fp_line
			(start 0.12065 -0.2794)
			(end 0.12065 -0.3048)
			(stroke
				(width 0.1)
				(type default)
			)
			(layer "F.Fab")
		)
		(fp_line
			(start 0.67945 -0.3048)
			(end 0.67945 0.3048)
			(stroke
				(width 0.1)
				(type default)
			)
			(layer "F.Fab")
		)
		(fp_line
			(start 0.67945 0.3048)
			(end 0.120396 0.3048)
			(stroke
				(width 0.1)
				(type default)
			)
			(layer "F.Fab")
		)
		(pad "1" smd circle
			(at -0.40005 0)
			(size 0 0)
			(layers "F.Cu" "F.Mask" "F.Paste")
			(net "P5V_STBY")
		)
		(pad "2" smd circle
			(at 0.40005 0)
			(size 0 0)
			(layers "F.Cu" "F.Mask" "F.Paste")
			(net "GND")
		)
	)
	(footprint ""
		(layer "F.Cu")
		(at 17.145 -62.103)
		(property "Reference" "C5"
			(at 1.651 0.15367 0)
			(unlocked yes)
			(layer "F.SilkS")
			(effects
				(font
					(size 0.7874 0.5842)
					(thickness 0.1524)
				)
			)
		)
		(property "Value" ""
			(at 0 0 0)
			(layer "F.Fab")
			(effects
				(font
					(size 1.27 1.27)
				)
			)
		)
		(duplicate_pad_numbers_are_jumpers no)
		(fp_line
			(start -0.7874 -0.4064)
			(end 0.7874 -0.4064)
			(stroke
				(width 0.1524)
				(type default)
			)
			(layer "F.SilkS")
		)
		(fp_line
			(start -0.7874 0.4064)
			(end -0.7874 -0.4064)
			(stroke
				(width 0.1524)
				(type default)
			)
			(layer "F.SilkS")
		)
		(fp_line
			(start 0.7874 -0.4064)
			(end 0.7874 0.4064)
			(stroke
				(width 0.1524)
				(type default)
			)
			(layer "F.SilkS")
		)
		(fp_line
			(start 0.7874 0.4064)
			(end -0.7874 0.4064)
			(stroke
				(width 0.1524)
				(type default)
			)
			(layer "F.SilkS")
		)
		(fp_line
			(start -0.67945 -0.305054)
			(end -0.12065 -0.305054)
			(stroke
				(width 0.1)
				(type default)
			)
			(layer "F.Fab")
		)
		(fp_line
			(start -0.67945 0.3048)
			(end -0.67945 -0.305054)
			(stroke
				(width 0.1)
				(type default)
			)
			(layer "F.Fab")
		)
		(fp_line
			(start -0.12065 -0.305054)
			(end -0.12065 -0.2794)
			(stroke
				(width 0.1)
				(type default)
			)
			(layer "F.Fab")
		)
		(fp_line
			(start -0.12065 -0.2794)
			(end 0.12065 -0.2794)
			(stroke
				(width 0.1)
				(type default)
			)
			(layer "F.Fab")
		)
		(fp_line
			(start -0.12065 0.2794)
			(end -0.12065 0.3048)
			(stroke
				(width 0.1)
				(type default)
			)
			(layer "F.Fab")
		)
		(fp_line
			(start -0.12065 0.3048)
			(end -0.67945 0.3048)
			(stroke
				(width 0.1)
				(type default)
			)
			(layer "F.Fab")
		)
		(fp_line
			(start 0.120396 0.2794)
			(end -0.12065 0.2794)
			(stroke
				(width 0.1)
				(type default)
			)
			(layer "F.Fab")
		)
		(fp_line
			(start 0.120396 0.3048)
			(end 0.120396 0.2794)
			(stroke
				(width 0.1)
				(type default)
			)
			(layer "F.Fab")
		)
		(fp_line
			(start 0.12065 -0.3048)
			(end 0.67945 -0.3048)
			(stroke
				(width 0.1)
				(type default)
			)
			(layer "F.Fab")
		)
		(fp_line
			(start 0.12065 -0.2794)
			(end 0.12065 -0.3048)
			(stroke
				(width 0.1)
				(type default)
			)
			(layer "F.Fab")
		)
		(fp_line
			(start 0.67945 -0.3048)
			(end 0.67945 0.3048)
			(stroke
				(width 0.1)
				(type default)
			)
			(layer "F.Fab")
		)
		(fp_line
			(start 0.67945 0.3048)
			(end 0.120396 0.3048)
			(stroke
				(width 0.1)
				(type default)
			)
			(layer "F.Fab")
		)
		(pad "1" smd circle
			(at -0.40005 0)
			(size 0 0)
			(layers "F.Cu" "F.Mask" "F.Paste")
			(net "P3V3_STBY")
		)
		(pad "2" smd circle
			(at 0.40005 0)
			(size 0 0)
			(layers "F.Cu" "F.Mask" "F.Paste")
			(net "GND")
		)
	)
	(footprint ""
		(layer "F.Cu")
		(at 5.969 -55.245)
		(property "Reference" "R22"
			(at -2.794 0.40767 0)
			(unlocked yes)
			(layer "F.SilkS")
			(effects
				(font
					(size 0.7874 0.5842)
					(thickness 0.1524)
				)
			)
		)
		(property "Value" ""
			(at 0 0 0)
			(layer "F.Fab")
			(effects
				(font
					(size 1.27 1.27)
				)
			)
		)
		(duplicate_pad_numbers_are_jumpers no)
		(fp_line
			(start -0.7874 -0.4064)
			(end 0.7874 -0.4064)
			(stroke
				(width 0.1524)
				(type default)
			)
			(layer "F.SilkS")
		)
		(fp_line
			(start -0.7874 0.4064)
			(end -0.7874 -0.4064)
			(stroke
				(width 0.1524)
				(type default)
			)
			(layer "F.SilkS")
		)
		(fp_line
			(start 0.7874 -0.4064)
			(end 0.7874 0.4064)
			(stroke
				(width 0.1524)
				(type default)
			)
			(layer "F.SilkS")
		)
		(fp_line
			(start 0.7874 0.4064)
			(end -0.7874 0.4064)
			(stroke
				(width 0.1524)
				(type default)
			)
			(layer "F.SilkS")
		)
		(fp_line
			(start -0.67945 -0.305054)
			(end -0.12065 -0.305054)
			(stroke
				(width 0.1)
				(type default)
			)
			(layer "F.Fab")
		)
		(fp_line
			(start -0.67945 0.3048)
			(end -0.67945 -0.305054)
			(stroke
				(width 0.1)
				(type default)
			)
			(layer "F.Fab")
		)
		(fp_line
			(start -0.12065 -0.305054)
			(end -0.12065 -0.2794)
			(stroke
				(width 0.1)
				(type default)
			)
			(layer "F.Fab")
		)
		(fp_line
			(start -0.12065 -0.2794)
			(end 0.12065 -0.2794)
			(stroke
				(width 0.1)
				(type default)
			)
			(layer "F.Fab")
		)
		(fp_line
			(start -0.12065 0.2794)
			(end -0.12065 0.3048)
			(stroke
				(width 0.1)
				(type default)
			)
			(layer "F.Fab")
		)
		(fp_line
			(start -0.12065 0.3048)
			(end -0.67945 0.3048)
			(stroke
				(width 0.1)
				(type default)
			)
			(layer "F.Fab")
		)
		(fp_line
			(start 0.120396 0.2794)
			(end -0.12065 0.2794)
			(stroke
				(width 0.1)
				(type default)
			)
			(layer "F.Fab")
		)
		(fp_line
			(start 0.120396 0.3048)
			(end 0.120396 0.2794)
			(stroke
				(width 0.1)
				(type default)
			)
			(layer "F.Fab")
		)
		(fp_line
			(start 0.12065 -0.3048)
			(end 0.67945 -0.3048)
			(stroke
				(width 0.1)
				(type default)
			)
			(layer "F.Fab")
		)
		(fp_line
			(start 0.12065 -0.2794)
			(end 0.12065 -0.3048)
			(stroke
				(width 0.1)
				(type default)
			)
			(layer "F.Fab")
		)
		(fp_line
			(start 0.67945 -0.3048)
			(end 0.67945 0.3048)
			(stroke
				(width 0.1)
				(type default)
			)
			(layer "F.Fab")
		)
		(fp_line
			(start 0.67945 0.3048)
			(end 0.120396 0.3048)
			(stroke
				(width 0.1)
				(type default)
			)
			(layer "F.Fab")
		)
		(pad "1" smd circle
			(at -0.40005 0)
			(size 0 0)
			(layers "F.Cu" "F.Mask" "F.Paste")
			(net "P3V3_STBY")
		)
		(pad "2" smd circle
			(at 0.40005 0)
			(size 0 0)
			(layers "F.Cu" "F.Mask" "F.Paste")
			(net "REV_ID<1>")
		)
	)
	(footprint ""
		(layer "F.Cu")
		(at 20.701 -63.373 -90)
		(property "Reference" "R68"
			(at -0.254 -2.18567 90)
			(unlocked yes)
			(layer "F.SilkS")
			(effects
				(font
					(size 0.7874 0.5842)
					(thickness 0.1524)
				)
			)
		)
		(property "Value" ""
			(at 0 0 270)
			(layer "F.Fab")
			(effects
				(font
					(size 1.27 1.27)
				)
			)
		)
		(duplicate_pad_numbers_are_jumpers no)
		(fp_line
			(start -0.7874 0.4064)
			(end -0.7874 -0.4064)
			(stroke
				(width 0.1524)
				(type default)
			)
			(layer "F.SilkS")
		)
		(fp_line
			(start 0.7874 0.4064)
			(end -0.7874 0.4064)
			(stroke
				(width 0.1524)
				(type default)
			)
			(layer "F.SilkS")
		)
		(fp_line
			(start -0.7874 -0.4064)
			(end 0.7874 -0.4064)
			(stroke
				(width 0.1524)
				(type default)
			)
			(layer "F.SilkS")
		)
		(fp_line
			(start 0.7874 -0.4064)
			(end 0.7874 0.4064)
			(stroke
				(width 0.1524)
				(type default)
			)
			(layer "F.SilkS")
		)
		(fp_line
			(start -0.67945 0.3048)
			(end -0.67945 -0.305054)
			(stroke
				(width 0.1)
				(type default)
			)
			(layer "F.Fab")
		)
		(fp_line
			(start -0.12065 0.3048)
			(end -0.67945 0.3048)
			(stroke
				(width 0.1)
				(type default)
			)
			(layer "F.Fab")
		)
		(fp_line
			(start 0.120396 0.3048)
			(end 0.120396 0.2794)
			(stroke
				(width 0.1)
				(type default)
			)
			(layer "F.Fab")
		)
		(fp_line
			(start 0.67945 0.3048)
			(end 0.120396 0.3048)
			(stroke
				(width 0.1)
				(type default)
			)
			(layer "F.Fab")
		)
		(fp_line
			(start -0.12065 0.2794)
			(end -0.12065 0.3048)
			(stroke
				(width 0.1)
				(type default)
			)
			(layer "F.Fab")
		)
		(fp_line
			(start 0.120396 0.2794)
			(end -0.12065 0.2794)
			(stroke
				(width 0.1)
				(type default)
			)
			(layer "F.Fab")
		)
		(fp_line
			(start -0.12065 -0.2794)
			(end 0.12065 -0.2794)
			(stroke
				(width 0.1)
				(type default)
			)
			(layer "F.Fab")
		)
		(fp_line
			(start 0.12065 -0.2794)
			(end 0.12065 -0.3048)
			(stroke
				(width 0.1)
				(type default)
			)
			(layer "F.Fab")
		)
		(fp_line
			(start 0.12065 -0.3048)
			(end 0.67945 -0.3048)
			(stroke
				(width 0.1)
				(type default)
			)
			(layer "F.Fab")
		)
		(fp_line
			(start 0.67945 -0.3048)
			(end 0.67945 0.3048)
			(stroke
				(width 0.1)
				(type default)
			)
			(layer "F.Fab")
		)
		(fp_line
			(start -0.67945 -0.305054)
			(end -0.12065 -0.305054)
			(stroke
				(width 0.1)
				(type default)
			)
			(layer "F.Fab")
		)
		(fp_line
			(start -0.12065 -0.305054)
			(end -0.12065 -0.2794)
			(stroke
				(width 0.1)
				(type default)
			)
			(layer "F.Fab")
		)
		(pad "1" smd circle
			(at -0.40005 0 270)
			(size 0 0)
			(layers "F.Cu" "F.Mask" "F.Paste")
			(net "SMB_SWB_SDA")
		)
		(pad "2" smd circle
			(at 0.40005 0 270)
			(size 0 0)
			(layers "F.Cu" "F.Mask" "F.Paste")
			(net "SMB_SDA")
		)
	)
)
